# T6G (Grand Teton) — schematic netlist excerpt (pin names and nets, part order shuffled) for the footprints in the layout excerpt that follows; sources: Cadence DE-HDL packaged netlist, KiCad conversion of 04192023_DAF0TMB3IC0_F0TG_MB_C_brd_V02_OCP.brd

R6237  Q_RES  0 5% EMPTY  pkg 0402LF  page 267 : A = A_HSC_LOW_GATE ; B = GND
R8105  Q_RES  0 5% EMPTY  pkg 0402LF  page 242 : A = FM_AC_PWR_BTN_PLD_ISO_R_N ; B = FM_AC_PWR_BTN_PLD_ISO_N
C388  Q_CAP  0.1UF 10V 10% X7S  pkg C0201  page 345 : A = P0V9_CPU1_RT_2D ; B = GND

(kicad_pcb
	(version 20260206)
	(generator "pcbnew")
	(generator_version "10.0")
	(general
		(thickness 1.6)
		(legacy_teardrops no)
	)
	(paper "A4")
	(title_block
		(title "04192023_DAF0TMB3IC0_F0TG_MB_C_brd_V02_OCP.brd")
		(comment 1 "Grand Teton / footprints 6980-6982 of 8354")
	)
	(layers
		(0 "F.Cu" signal "TOP")
		(4 "In1.Cu" signal "GND")
		(6 "In2.Cu" signal "IN1")
		(8 "In3.Cu" signal "GND1")
		(10 "In4.Cu" signal "IN2")
		(12 "In5.Cu" signal "GND2")
		(14 "In6.Cu" signal "IN3")
		(16 "In7.Cu" signal "GND3")
		(18 "In8.Cu" signal "VCC")
		(20 "In9.Cu" signal "VCC1")
		(22 "In10.Cu" signal "GND4")
		(24 "In11.Cu" signal "IN4")
		(26 "In12.Cu" signal "GND5")
		(28 "In13.Cu" signal "IN5")
		(30 "In14.Cu" signal "GND6")
		(32 "In15.Cu" signal "IN6")
		(34 "In16.Cu" signal "GND7")
		(2 "B.Cu" signal "BOTTOM")
		(9 "F.Adhes" user "F.Adhesive")
		(11 "B.Adhes" user "B.Adhesive")
		(13 "F.Paste" user "Package Geometry/Pastemask Top")
		(15 "B.Paste" user "Package Geometry/Pastemask Bottom")
		(5 "F.SilkS" user "Ref Des/Silkscreen Top")
		(7 "B.SilkS" user "Ref Des/Silkscreen Bottom")
		(1 "F.Mask" user "Board Geometry/Soldermask Top")
		(3 "B.Mask" user "Board Geometry/Soldermask Bottom")
		(17 "Dwgs.User" user "User.Drawings")
		(19 "Cmts.User" user "User.Comments")
		(21 "Eco1.User" user "User.Eco1")
		(23 "Eco2.User" user "User.Eco2")
		(25 "Edge.Cuts" user "Board Geometry/Outline")
		(27 "Margin" user)
		(31 "F.CrtYd" user "Package Geometry/Place Bound Top")
		(29 "B.CrtYd" user "Package Geometry/Place Bound Bottom")
		(35 "F.Fab" user "Ref Des/Assembly Top")
		(33 "B.Fab" user "Ref Des/Assembly Bottom")
	)
	(footprint ""
		(layer "B.Cu")
		(at 199.517 -136.652 90)
		(property "Reference" "R8105"
			(at 0 0 90)
			(layer "B.SilkS")
			(hide yes)
			(effects
				(font
					(size 1.27 1.27)
				)
				(justify mirror)
			)
		)
		(property "Value" ""
			(at 0 0 90)
			(layer "B.Fab")
			(effects
				(font
					(size 1.27 1.27)
				)
				(justify mirror)
			)
		)
		(duplicate_pad_numbers_are_jumpers no)
		(fp_line
			(start 0.7874 -0.4064)
			(end -0.7874 -0.4064)
			(stroke
				(width 0.1524)
				(type default)
			)
			(layer "B.SilkS")
		)
		(fp_line
			(start -0.7874 -0.4064)
			(end -0.7874 0.4064)
			(stroke
				(width 0.1524)
				(type default)
			)
			(layer "B.SilkS")
		)
		(fp_line
			(start 0.7874 0.4064)
			(end 0.7874 -0.4064)
			(stroke
				(width 0.1524)
				(type default)
			)
			(layer "B.SilkS")
		)
		(fp_line
			(start -0.7874 0.4064)
			(end 0.7874 0.4064)
			(stroke
				(width 0.1524)
				(type default)
			)
			(layer "B.SilkS")
		)
		(fp_line
			(start 0.67945 -0.305054)
			(end 0.12065 -0.305054)
			(stroke
				(width 0.1)
				(type default)
			)
			(layer "B.Fab")
		)
		(fp_line
			(start 0.12065 -0.305054)
			(end 0.12065 -0.2794)
			(stroke
				(width 0.1)
				(type default)
			)
			(layer "B.Fab")
		)
		(fp_line
			(start -0.12065 -0.3048)
			(end -0.67945 -0.3048)
			(stroke
				(width 0.1)
				(type default)
			)
			(layer "B.Fab")
		)
		(fp_line
			(start -0.67945 -0.3048)
			(end -0.67945 0.3048)
			(stroke
				(width 0.1)
				(type default)
			)
			(layer "B.Fab")
		)
		(fp_line
			(start 0.12065 -0.2794)
			(end -0.12065 -0.2794)
			(stroke
				(width 0.1)
				(type default)
			)
			(layer "B.Fab")
		)
		(fp_line
			(start -0.12065 -0.2794)
			(end -0.12065 -0.3048)
			(stroke
				(width 0.1)
				(type default)
			)
			(layer "B.Fab")
		)
		(fp_line
			(start 0.12065 0.2794)
			(end 0.12065 0.3048)
			(stroke
				(width 0.1)
				(type default)
			)
			(layer "B.Fab")
		)
		(fp_line
			(start -0.120396 0.2794)
			(end 0.12065 0.2794)
			(stroke
				(width 0.1)
				(type default)
			)
			(layer "B.Fab")
		)
		(fp_line
			(start 0.67945 0.3048)
			(end 0.67945 -0.305054)
			(stroke
				(width 0.1)
				(type default)
			)
			(layer "B.Fab")
		)
		(fp_line
			(start 0.12065 0.3048)
			(end 0.67945 0.3048)
			(stroke
				(width 0.1)
				(type default)
			)
			(layer "B.Fab")
		)
		(fp_line
			(start -0.120396 0.3048)
			(end -0.120396 0.2794)
			(stroke
				(width 0.1)
				(type default)
			)
			(layer "B.Fab")
		)
		(fp_line
			(start -0.67945 0.3048)
			(end -0.120396 0.3048)
			(stroke
				(width 0.1)
				(type default)
			)
			(layer "B.Fab")
		)
		(pad "1" smd circle
			(at 0.40005 0 270)
			(size 0 0)
			(layers "B.Cu" "B.Mask" "B.Paste")
			(net "FM_AC_PWR_BTN_PLD_ISO_R_N")
		)
		(pad "2" smd circle
			(at -0.40005 0 270)
			(size 0 0)
			(layers "B.Cu" "B.Mask" "B.Paste")
			(net "FM_AC_PWR_BTN_PLD_ISO_N")
		)
	)
	(footprint ""
		(layer "B.Cu")
		(at 173.71314 -427.92904 180)
		(property "Reference" "R6237"
			(at 0 0 0)
			(layer "B.SilkS")
			(hide yes)
			(effects
				(font
					(size 1.27 1.27)
				)
				(justify mirror)
			)
		)
		(property "Value" ""
			(at 0 0 0)
			(layer "B.Fab")
			(effects
				(font
					(size 1.27 1.27)
				)
				(justify mirror)
			)
		)
		(duplicate_pad_numbers_are_jumpers no)
		(fp_line
			(start 0.7874 0.4064)
			(end 0.7874 -0.4064)
			(stroke
				(width 0.1524)
				(type default)
			)
			(layer "B.SilkS")
		)
		(fp_line
			(start 0.7874 -0.4064)
			(end -0.7874 -0.4064)
			(stroke
				(width 0.1524)
				(type default)
			)
			(layer "B.SilkS")
		)
		(fp_line
			(start -0.7874 0.4064)
			(end 0.7874 0.4064)
			(stroke
				(width 0.1524)
				(type default)
			)
			(layer "B.SilkS")
		)
		(fp_line
			(start -0.7874 -0.4064)
			(end -0.7874 0.4064)
			(stroke
				(width 0.1524)
				(type default)
			)
			(layer "B.SilkS")
		)
		(fp_line
			(start 0.67945 0.3048)
			(end 0.67945 -0.305054)
			(stroke
				(width 0.1)
				(type default)
			)
			(layer "B.Fab")
		)
		(fp_line
			(start 0.67945 -0.305054)
			(end 0.12065 -0.305054)
			(stroke
				(width 0.1)
				(type default)
			)
			(layer "B.Fab")
		)
		(fp_line
			(start 0.12065 0.3048)
			(end 0.67945 0.3048)
			(stroke
				(width 0.1)
				(type default)
			)
			(layer "B.Fab")
		)
		(fp_line
			(start 0.12065 0.2794)
			(end 0.12065 0.3048)
			(stroke
				(width 0.1)
				(type default)
			)
			(layer "B.Fab")
		)
		(fp_line
			(start 0.12065 -0.2794)
			(end -0.12065 -0.2794)
			(stroke
				(width 0.1)
				(type default)
			)
			(layer "B.Fab")
		)
		(fp_line
			(start 0.12065 -0.305054)
			(end 0.12065 -0.2794)
			(stroke
				(width 0.1)
				(type default)
			)
			(layer "B.Fab")
		)
		(fp_line
			(start -0.120396 0.3048)
			(end -0.120396 0.2794)
			(stroke
				(width 0.1)
				(type default)
			)
			(layer "B.Fab")
		)
		(fp_line
			(start -0.120396 0.2794)
			(end 0.12065 0.2794)
			(stroke
				(width 0.1)
				(type default)
			)
			(layer "B.Fab")
		)
		(fp_line
			(start -0.12065 -0.2794)
			(end -0.12065 -0.3048)
			(stroke
				(width 0.1)
				(type default)
			)
			(layer "B.Fab")
		)
		(fp_line
			(start -0.12065 -0.3048)
			(end -0.67945 -0.3048)
			(stroke
				(width 0.1)
				(type default)
			)
			(layer "B.Fab")
		)
		(fp_line
			(start -0.67945 0.3048)
			(end -0.120396 0.3048)
			(stroke
				(width 0.1)
				(type default)
			)
			(layer "B.Fab")
		)
		(fp_line
			(start -0.67945 -0.3048)
			(end -0.67945 0.3048)
			(stroke
				(width 0.1)
				(type default)
			)
			(layer "B.Fab")
		)
		(pad "1" smd circle
			(at 0.40005 0)
			(size 0 0)
			(layers "B.Cu" "B.Mask" "B.Paste")
			(net "A_HSC_LOW_GATE")
		)
		(pad "2" smd circle
			(at -0.40005 0)
			(size 0 0)
			(layers "B.Cu" "B.Mask" "B.Paste")
			(net "GND")
		)
	)
	(footprint ""
		(layer "B.Cu")
		(at 159.14624 -388.011162 -90)
		(property "Reference" "C388"
			(at 0 0 90)
			(layer "B.SilkS")
			(hide yes)
			(effects
				(font
					(size 1.27 1.27)
				)
				(justify mirror)
			)
		)
		(property "Value" ""
			(at 0 0 90)
			(layer "B.Fab")
			(effects
				(font
					(size 1.27 1.27)
				)
				(justify mirror)
			)
		)
		(duplicate_pad_numbers_are_jumpers no)
		(fp_line
			(start -0.299974 0.150114)
			(end 0.299974 0.150114)
			(stroke
				(width 0.1)
				(type default)
			)
			(layer "B.Fab")
		)
		(fp_line
			(start 0.299974 0.150114)
			(end 0.299974 -0.150114)
			(stroke
				(width 0.1)
				(type default)
			)
			(layer "B.Fab")
		)
		(fp_line
			(start -0.299974 -0.150114)
			(end -0.299974 0.150114)
			(stroke
				(width 0.1)
				(type default)
			)
			(layer "B.Fab")
		)
		(fp_line
			(start 0.299974 -0.150114)
			(end -0.299974 -0.150114)
			(stroke
				(width 0.1)
				(type default)
			)
			(layer "B.Fab")
		)
		(pad "1" smd rect
			(at 0.2667 0 90)
			(size 0.3048 0.381)
			(layers "B.Cu" "B.Mask" "B.Paste")
			(net "P0V9_CPU1_RT_2D")
		)
		(pad "2" smd rect
			(at -0.2667 0 90)
			(size 0.3048 0.381)
			(layers "B.Cu" "B.Mask" "B.Paste")
			(net "GND")
		)
	)
)
